(kicad_pcb
	(version 20260206)
	(generator "pcbnew")
	(generator_version "10.0")
	(general
		(thickness 1.6)
		(legacy_teardrops no)
	)
	(paper "A4")
	(title_block
		(title "03242023_DA0F0TMBIJ0_F0T_Motherboard_J_brd_V01_OCP.brd")
		(comment 1 "Grand Teton / footprints 2360-2365 of 6105")
	)
	(layers
		(0 "F.Cu" signal "TOP")
		(4 "In1.Cu" signal "GND")
		(6 "In2.Cu" signal "IN1")
		(8 "In3.Cu" signal "GND1")
		(10 "In4.Cu" signal "IN2")
		(12 "In5.Cu" signal "GND2")
		(14 "In6.Cu" signal "IN3")
		(16 "In7.Cu" signal "GND3")
		(18 "In8.Cu" signal "VCC")
		(20 "In9.Cu" signal "VCC1")
		(22 "In10.Cu" signal "GND4")
		(24 "In11.Cu" signal "IN4")
		(26 "In12.Cu" signal "GND5")
		(28 "In13.Cu" signal "IN5")
		(30 "In14.Cu" signal "GND6")
		(32 "In15.Cu" signal "IN6")
		(34 "In16.Cu" signal "GND7")
		(2 "B.Cu" signal "BOTTOM")
		(9 "F.Adhes" user "F.Adhesive")
		(11 "B.Adhes" user "B.Adhesive")
		(13 "F.Paste" user "Package Geometry/Pastemask Top")
		(15 "B.Paste" user "Package Geometry/Pastemask Bottom")
		(5 "F.SilkS" user "Ref Des/Silkscreen Top")
		(7 "B.SilkS" user "Ref Des/Silkscreen Bottom")
		(1 "F.Mask" user "Board Geometry/Soldermask Top")
		(3 "B.Mask" user "Board Geometry/Soldermask Bottom")
		(17 "Dwgs.User" user "User.Drawings")
		(19 "Cmts.User" user "User.Comments")
		(21 "Eco1.User" user "User.Eco1")
		(23 "Eco2.User" user "User.Eco2")
		(25 "Edge.Cuts" user "Board Geometry/Outline")
		(27 "Margin" user)
		(31 "F.CrtYd" user "Package Geometry/Place Bound Top")
		(29 "B.CrtYd" user "Package Geometry/Place Bound Bottom")
		(35 "F.Fab" user "Ref Des/Assembly Top")
		(33 "B.Fab" user "Ref Des/Assembly Bottom")
	)
	(footprint ""
		(layer "F.Cu")
		(at 15.288006 -105.53573 90)
		(property "Reference" "R2790"
			(at 0 0 90)
			(layer "F.SilkS")
			(hide yes)
			(effects
				(font
					(size 1.27 1.27)
				)
			)
		)
		(property "Value" ""
			(at 0 0 90)
			(layer "F.Fab")
			(effects
				(font
					(size 1.27 1.27)
				)
			)
		)
		(duplicate_pad_numbers_are_jumpers no)
		(fp_line
			(start -0.02667 -0.4064)
			(end 0.7874 -0.4064)
			(stroke
				(width 0.1524)
				(type default)
			)
			(layer "F.SilkS")
		)
		(fp_line
			(start 0.7874 0.4064)
			(end 0.00127 0.4064)
			(stroke
				(width 0.1524)
				(type default)
			)
			(layer "F.SilkS")
		)
		(fp_line
			(start -0.7874 0.4064)
			(end -0.7874 -0.4064)
			(stroke
				(width 0.1524)
				(type default)
			)
			(layer "F.SilkS")
		)
		(fp_line
			(start -0.12065 -0.305054)
			(end -0.12065 -0.2794)
			(stroke
				(width 0.1)
				(type default)
			)
			(layer "F.Fab")
		)
		(fp_line
			(start -0.67945 -0.305054)
			(end -0.12065 -0.305054)
			(stroke
				(width 0.1)
				(type default)
			)
			(layer "F.Fab")
		)
		(fp_line
			(start 0.67945 -0.3048)
			(end 0.67945 0.3048)
			(stroke
				(width 0.1)
				(type default)
			)
			(layer "F.Fab")
		)
		(fp_line
			(start 0.12065 -0.3048)
			(end 0.67945 -0.3048)
			(stroke
				(width 0.1)
				(type default)
			)
			(layer "F.Fab")
		)
		(fp_line
			(start 0.12065 -0.2794)
			(end 0.12065 -0.3048)
			(stroke
				(width 0.1)
				(type default)
			)
			(layer "F.Fab")
		)
		(fp_line
			(start -0.12065 -0.2794)
			(end 0.12065 -0.2794)
			(stroke
				(width 0.1)
				(type default)
			)
			(layer "F.Fab")
		)
		(fp_line
			(start 0.120396 0.2794)
			(end -0.12065 0.2794)
			(stroke
				(width 0.1)
				(type default)
			)
			(layer "F.Fab")
		)
		(fp_line
			(start -0.12065 0.2794)
			(end -0.12065 0.3048)
			(stroke
				(width 0.1)
				(type default)
			)
			(layer "F.Fab")
		)
		(fp_line
			(start 0.67945 0.3048)
			(end 0.120396 0.3048)
			(stroke
				(width 0.1)
				(type default)
			)
			(layer "F.Fab")
		)
		(fp_line
			(start 0.120396 0.3048)
			(end 0.120396 0.2794)
			(stroke
				(width 0.1)
				(type default)
			)
			(layer "F.Fab")
		)
		(fp_line
			(start -0.12065 0.3048)
			(end -0.67945 0.3048)
			(stroke
				(width 0.1)
				(type default)
			)
			(layer "F.Fab")
		)
		(fp_line
			(start -0.67945 0.3048)
			(end -0.67945 -0.305054)
			(stroke
				(width 0.1)
				(type default)
			)
			(layer "F.Fab")
		)
		(pad "1" smd rect
			(at -0.40005 0 270)
			(size 0.4572 0.508)
			(layers "F.Cu" "F.Mask" "F.Paste")
			(net "USB2_HOST_BMC_B_DP")
		)
		(pad "2" smd rect
			(at 0.40005 0 270)
			(size 0.4572 0.508)
			(layers "F.Cu" "F.Mask" "F.Paste")
			(net "USB2_HOST_BMC_B_BUF_DP")
		)
	)
	(footprint ""
		(layer "F.Cu")
		(at 68.179696 -70.78599)
		(property "Reference" "D69"
			(at -36.052506 50.178462 90)
			(unlocked yes)
			(layer "F.SilkS")
			(effects
				(font
					(size 0.635 0.4064)
					(thickness 0.1524)
				)
				(justify left)
			)
		)
		(property "Value" ""
			(at 0 0 0)
			(layer "F.Fab")
			(effects
				(font
					(size 1.27 1.27)
				)
			)
		)
		(duplicate_pad_numbers_are_jumpers no)
		(fp_line
			(start -0.90678 0.4826)
			(end -0.90678 -0.4699)
			(stroke
				(width 0.1524)
				(type default)
			)
			(layer "F.SilkS")
		)
		(fp_line
			(start -0.89408 -0.4826)
			(end 0.90678 -0.4826)
			(stroke
				(width 0.1524)
				(type default)
			)
			(layer "F.SilkS")
		)
		(fp_line
			(start -0.79248 -0.4826)
			(end 1.03378 -0.4826)
			(stroke
				(width 0.1524)
				(type default)
			)
			(layer "F.SilkS")
		)
		(fp_line
			(start -0.64008 -0.4826)
			(end 1.16078 -0.4826)
			(stroke
				(width 0.1524)
				(type default)
			)
			(layer "F.SilkS")
		)
		(fp_line
			(start 0.90678 -0.4826)
			(end 0.90678 0.4826)
			(stroke
				(width 0.1524)
				(type default)
			)
			(layer "F.SilkS")
		)
		(fp_line
			(start 0.90678 0.4826)
			(end -0.90678 0.4826)
			(stroke
				(width 0.1524)
				(type default)
			)
			(layer "F.SilkS")
		)
		(fp_line
			(start 1.03378 -0.4826)
			(end 1.03378 0.4826)
			(stroke
				(width 0.1524)
				(type default)
			)
			(layer "F.SilkS")
		)
		(fp_line
			(start 1.03378 0.4826)
			(end -0.79248 0.4826)
			(stroke
				(width 0.1524)
				(type default)
			)
			(layer "F.SilkS")
		)
		(fp_line
			(start 1.16078 -0.4826)
			(end 1.16078 0.4826)
			(stroke
				(width 0.1524)
				(type default)
			)
			(layer "F.SilkS")
		)
		(fp_line
			(start 1.16078 0.4826)
			(end -0.64008 0.4826)
			(stroke
				(width 0.1524)
				(type default)
			)
			(layer "F.SilkS")
		)
		(fp_line
			(start -0.499872 -0.249936)
			(end 0.499872 -0.249936)
			(stroke
				(width 0.1)
				(type default)
			)
			(layer "F.Fab")
		)
		(fp_line
			(start -0.499872 0.249936)
			(end -0.499872 -0.249936)
			(stroke
				(width 0.1)
				(type default)
			)
			(layer "F.Fab")
		)
		(fp_line
			(start 0.499872 -0.249936)
			(end 0.499872 0.249936)
			(stroke
				(width 0.1)
				(type default)
			)
			(layer "F.Fab")
		)
		(fp_line
			(start 0.499872 0.249936)
			(end -0.499872 0.249936)
			(stroke
				(width 0.1)
				(type default)
			)
			(layer "F.Fab")
		)
		(pad "A" smd rect
			(at -0.47498 0)
			(size 0.6096 0.7112)
			(layers "F.Cu" "F.Mask" "F.Paste")
			(net "LED_RST_PLD_CPU1_DRAM_AB_N")
		)
		(pad "C" smd rect
			(at 0.47498 0)
			(size 0.6096 0.7112)
			(layers "F.Cu" "F.Mask" "F.Paste")
			(net "LED_RST_PLD_CPU1_DRAM_AB_N_D")
		)
	)
	(footprint ""
		(layer "F.Cu")
		(at 237.401608 -404.721822 180)
		(property "Reference" "PR3984"
			(at 0 0 180)
			(layer "F.SilkS")
			(hide yes)
			(effects
				(font
					(size 1.27 1.27)
				)
			)
		)
		(property "Value" ""
			(at 0 0 180)
			(layer "F.Fab")
			(effects
				(font
					(size 1.27 1.27)
				)
			)
		)
		(duplicate_pad_numbers_are_jumpers no)
		(fp_line
			(start 0.7874 0.4064)
			(end -0.7874 0.4064)
			(stroke
				(width 0.1524)
				(type default)
			)
			(layer "F.SilkS")
		)
		(fp_line
			(start 0.7874 -0.4064)
			(end 0.7874 0.4064)
			(stroke
				(width 0.1524)
				(type default)
			)
			(layer "F.SilkS")
		)
		(fp_line
			(start -0.7874 0.4064)
			(end -0.7874 -0.4064)
			(stroke
				(width 0.1524)
				(type default)
			)
			(layer "F.SilkS")
		)
		(fp_line
			(start -0.7874 -0.4064)
			(end 0.7874 -0.4064)
			(stroke
				(width 0.1524)
				(type default)
			)
			(layer "F.SilkS")
		)
		(fp_line
			(start 0.67945 0.3048)
			(end 0.120396 0.3048)
			(stroke
				(width 0.1)
				(type default)
			)
			(layer "F.Fab")
		)
		(fp_line
			(start 0.67945 -0.3048)
			(end 0.67945 0.3048)
			(stroke
				(width 0.1)
				(type default)
			)
			(layer "F.Fab")
		)
		(fp_line
			(start 0.12065 -0.2794)
			(end 0.12065 -0.3048)
			(stroke
				(width 0.1)
				(type default)
			)
			(layer "F.Fab")
		)
		(fp_line
			(start 0.12065 -0.3048)
			(end 0.67945 -0.3048)
			(stroke
				(width 0.1)
				(type default)
			)
			(layer "F.Fab")
		)
		(fp_line
			(start 0.120396 0.3048)
			(end 0.120396 0.2794)
			(stroke
				(width 0.1)
				(type default)
			)
			(layer "F.Fab")
		)
		(fp_line
			(start 0.120396 0.2794)
			(end -0.12065 0.2794)
			(stroke
				(width 0.1)
				(type default)
			)
			(layer "F.Fab")
		)
		(fp_line
			(start -0.12065 0.3048)
			(end -0.67945 0.3048)
			(stroke
				(width 0.1)
				(type default)
			)
			(layer "F.Fab")
		)
		(fp_line
			(start -0.12065 0.2794)
			(end -0.12065 0.3048)
			(stroke
				(width 0.1)
				(type default)
			)
			(layer "F.Fab")
		)
		(fp_line
			(start -0.12065 -0.2794)
			(end 0.12065 -0.2794)
			(stroke
				(width 0.1)
				(type default)
			)
			(layer "F.Fab")
		)
		(fp_line
			(start -0.12065 -0.305054)
			(end -0.12065 -0.2794)
			(stroke
				(width 0.1)
				(type default)
			)
			(layer "F.Fab")
		)
		(fp_line
			(start -0.67945 0.3048)
			(end -0.67945 -0.305054)
			(stroke
				(width 0.1)
				(type default)
			)
			(layer "F.Fab")
		)
		(fp_line
			(start -0.67945 -0.305054)
			(end -0.12065 -0.305054)
			(stroke
				(width 0.1)
				(type default)
			)
			(layer "F.Fab")
		)
		(pad "1" smd circle
			(at -0.40005 0 180)
			(size 0 0)
			(layers "F.Cu" "F.Mask" "F.Paste")
			(net "AGND_HSC")
		)
		(pad "2" smd circle
			(at 0.40005 0 180)
			(size 0 0)
			(layers "F.Cu" "F.Mask" "F.Paste")
			(net "HSC_MODE_4")
		)
	)
	(footprint ""
		(layer "F.Cu")
		(at 157.28188 -131.155948 -90)
		(property "Reference" "Q52"
			(at -2.55905 0.86614 0)
			(unlocked yes)
			(layer "F.SilkS")
			(effects
				(font
					(size 0.7874 0.5842)
					(thickness 0.1524)
				)
				(justify left)
			)
		)
		(property "Value" ""
			(at 0 0 270)
			(layer "F.Fab")
			(effects
				(font
					(size 1.27 1.27)
				)
			)
		)
		(duplicate_pad_numbers_are_jumpers no)
		(fp_line
			(start -1.603248 1.500124)
			(end -1.603248 -1.500124)
			(stroke
				(width 0.1524)
				(type default)
			)
			(layer "F.SilkS")
		)
		(fp_line
			(start 1.603248 1.500124)
			(end -1.603248 1.500124)
			(stroke
				(width 0.1524)
				(type default)
			)
			(layer "F.SilkS")
		)
		(fp_line
			(start -1.603248 -1.500124)
			(end 1.603248 -1.500124)
			(stroke
				(width 0.1524)
				(type default)
			)
			(layer "F.SilkS")
		)
		(fp_line
			(start 1.603248 -1.500124)
			(end 1.603248 1.500124)
			(stroke
				(width 0.1524)
				(type default)
			)
			(layer "F.SilkS")
		)
		(fp_line
			(start -0.700024 1.500124)
			(end 0.700024 1.500124)
			(stroke
				(width 0.1)
				(type default)
			)
			(layer "F.Fab")
		)
		(fp_line
			(start 0.700024 1.500124)
			(end 0.700024 0.219964)
			(stroke
				(width 0.1)
				(type default)
			)
			(layer "F.Fab")
		)
		(fp_line
			(start -1.249934 1.169924)
			(end -0.700024 1.169924)
			(stroke
				(width 0.1)
				(type default)
			)
			(layer "F.Fab")
		)
		(fp_line
			(start -0.700024 1.169924)
			(end -0.700024 1.500124)
			(stroke
				(width 0.1)
				(type default)
			)
			(layer "F.Fab")
		)
		(fp_line
			(start -1.249934 0.729996)
			(end -1.249934 1.169924)
			(stroke
				(width 0.1)
				(type default)
			)
			(layer "F.Fab")
		)
		(fp_line
			(start -0.6985 0.729996)
			(end -1.249934 0.729996)
			(stroke
				(width 0.1)
				(type default)
			)
			(layer "F.Fab")
		)
		(fp_line
			(start 0.700024 0.219964)
			(end 1.249934 0.219964)
			(stroke
				(width 0.1)
				(type default)
			)
			(layer "F.Fab")
		)
		(fp_line
			(start 1.249934 0.219964)
			(end 1.249934 -0.219964)
			(stroke
				(width 0.1)
				(type default)
			)
			(layer "F.Fab")
		)
		(fp_line
			(start 0.700024 -0.219964)
			(end 0.700024 -1.500124)
			(stroke
				(width 0.1)
				(type default)
			)
			(layer "F.Fab")
		)
		(fp_line
			(start 1.249934 -0.219964)
			(end 0.700024 -0.219964)
			(stroke
				(width 0.1)
				(type default)
			)
			(layer "F.Fab")
		)
		(fp_line
			(start -1.249934 -0.729996)
			(end -0.6985 -0.729996)
			(stroke
				(width 0.1)
				(type default)
			)
			(layer "F.Fab")
		)
		(fp_line
			(start -0.6985 -0.729996)
			(end -0.6985 0.729996)
			(stroke
				(width 0.1)
				(type default)
			)
			(layer "F.Fab")
		)
		(fp_line
			(start -1.249934 -1.169924)
			(end -1.249934 -0.729996)
			(stroke
				(width 0.1)
				(type default)
			)
			(layer "F.Fab")
		)
		(fp_line
			(start -0.700024 -1.169924)
			(end -1.249934 -1.169924)
			(stroke
				(width 0.1)
				(type default)
			)
			(layer "F.Fab")
		)
		(fp_line
			(start -0.700024 -1.500124)
			(end -0.700024 -1.169924)
			(stroke
				(width 0.1)
				(type default)
			)
			(layer "F.Fab")
		)
		(fp_line
			(start 0.700024 -1.500124)
			(end -0.700024 -1.500124)
			(stroke
				(width 0.1)
				(type default)
			)
			(layer "F.Fab")
		)
		(fp_rect
			(start -0.700024 1.500124)
			(end 0.700024 -1.500124)
			(stroke
				(width 0)
				(type default)
			)
			(fill no)
			(layer "F.Fab")
		)
		(pad "D" smd rect
			(at 0.999998 0 180)
			(size 0.8128 0.9144)
			(layers "F.Cu" "F.Mask" "F.Paste")
			(net "FM_COMP_P3V3_AUX_VIN_R")
		)
		(pad "G" smd rect
			(at -0.999998 -0.94996 180)
			(size 0.8128 0.9144)
			(layers "F.Cu" "F.Mask" "F.Paste")
			(net "PWRGD_P3V3_AUX_R2")
		)
		(pad "S" smd rect
			(at -0.999998 0.94996 180)
			(size 0.8128 0.9144)
			(layers "F.Cu" "F.Mask" "F.Paste")
			(net "GND")
		)
	)
	(footprint ""
		(layer "F.Cu")
		(at 78.586838 -402.371052 -90)
		(property "Reference" "C730"
			(at 0 0 270)
			(layer "F.SilkS")
			(hide yes)
			(effects
				(font
					(size 1.27 1.27)
				)
			)
		)
		(property "Value" ""
			(at 0 0 270)
			(layer "F.Fab")
			(effects
				(font
					(size 1.27 1.27)
				)
			)
		)
		(duplicate_pad_numbers_are_jumpers no)
		(fp_line
			(start -0.299974 0.150114)
			(end -0.299974 -0.150114)
			(stroke
				(width 0.1)
				(type default)
			)
			(layer "F.Fab")
		)
		(fp_line
			(start 0.299974 0.150114)
			(end -0.299974 0.150114)
			(stroke
				(width 0.1)
				(type default)
			)
			(layer "F.Fab")
		)
		(fp_line
			(start -0.299974 -0.150114)
			(end 0.299974 -0.150114)
			(stroke
				(width 0.1)
				(type default)
			)
			(layer "F.Fab")
		)
		(fp_line
			(start 0.299974 -0.150114)
			(end 0.299974 0.150114)
			(stroke
				(width 0.1)
				(type default)
			)
			(layer "F.Fab")
		)
		(pad "1" smd rect
			(at -0.2667 0 270)
			(size 0.3048 0.381)
			(layers "F.Cu" "F.Mask" "F.Paste")
			(net "P5E_CPU1_PE0_TX_C_DN<5>")
		)
		(pad "2" smd rect
			(at 0.2667 0 270)
			(size 0.3048 0.381)
			(layers "F.Cu" "F.Mask" "F.Paste")
			(net "P5E_CPU1_PE0_TX_DN<5>")
		)
	)
	(footprint ""
		(layer "F.Cu")
		(at 22.354032 -175.423576)
		(property "Reference" "PR502"
			(at 0 0 0)
			(layer "F.SilkS")
			(hide yes)
			(effects
				(font
					(size 1.27 1.27)
				)
			)
		)
		(property "Value" ""
			(at 0 0 0)
			(layer "F.Fab")
			(effects
				(font
					(size 1.27 1.27)
				)
			)
		)
		(duplicate_pad_numbers_are_jumpers no)
		(fp_line
			(start -0.7874 -0.4064)
			(end 0.7874 -0.4064)
			(stroke
				(width 0.1524)
				(type default)
			)
			(layer "F.SilkS")
		)
		(fp_line
			(start -0.7874 0.4064)
			(end -0.7874 -0.4064)
			(stroke
				(width 0.1524)
				(type default)
			)
			(layer "F.SilkS")
		)
		(fp_line
			(start 0.7874 -0.4064)
			(end 0.7874 0.4064)
			(stroke
				(width 0.1524)
				(type default)
			)
			(layer "F.SilkS")
		)
		(fp_line
			(start 0.7874 0.4064)
			(end -0.7874 0.4064)
			(stroke
				(width 0.1524)
				(type default)
			)
			(layer "F.SilkS")
		)
		(fp_line
			(start -0.67945 -0.305054)
			(end -0.12065 -0.305054)
			(stroke
				(width 0.1)
				(type default)
			)
			(layer "F.Fab")
		)
		(fp_line
			(start -0.67945 0.3048)
			(end -0.67945 -0.305054)
			(stroke
				(width 0.1)
				(type default)
			)
			(layer "F.Fab")
		)
		(fp_line
			(start -0.12065 -0.305054)
			(end -0.12065 -0.2794)
			(stroke
				(width 0.1)
				(type default)
			)
			(layer "F.Fab")
		)
		(fp_line
			(start -0.12065 -0.2794)
			(end 0.12065 -0.2794)
			(stroke
				(width 0.1)
				(type default)
			)
			(layer "F.Fab")
		)
		(fp_line
			(start -0.12065 0.2794)
			(end -0.12065 0.3048)
			(stroke
				(width 0.1)
				(type default)
			)
			(layer "F.Fab")
		)
		(fp_line
			(start -0.12065 0.3048)
			(end -0.67945 0.3048)
			(stroke
				(width 0.1)
				(type default)
			)
			(layer "F.Fab")
		)
		(fp_line
			(start 0.120396 0.2794)
			(end -0.12065 0.2794)
			(stroke
				(width 0.1)
				(type default)
			)
			(layer "F.Fab")
		)
		(fp_line
			(start 0.120396 0.3048)
			(end 0.120396 0.2794)
			(stroke
				(width 0.1)
				(type default)
			)
			(layer "F.Fab")
		)
		(fp_line
			(start 0.12065 -0.3048)
			(end 0.67945 -0.3048)
			(stroke
				(width 0.1)
				(type default)
			)
			(layer "F.Fab")
		)
		(fp_line
			(start 0.12065 -0.2794)
			(end 0.12065 -0.3048)
			(stroke
				(width 0.1)
				(type default)
			)
			(layer "F.Fab")
		)
		(fp_line
			(start 0.67945 -0.3048)
			(end 0.67945 0.3048)
			(stroke
				(width 0.1)
				(type default)
			)
			(layer "F.Fab")
		)
		(fp_line
			(start 0.67945 0.3048)
			(end 0.120396 0.3048)
			(stroke
				(width 0.1)
				(type default)
			)
			(layer "F.Fab")
		)
		(pad "1" smd circle
			(at -0.40005 0)
			(size 0 0)
			(layers "F.Cu" "F.Mask" "F.Paste")
			(net "PVNN_MAIN_CPU1_FB")
		)
		(pad "2" smd circle
			(at 0.40005 0)
			(size 0 0)
			(layers "F.Cu" "F.Mask" "F.Paste")
			(net "PVNN_MAIN_CPU1_FB_RC")
		)
	)
)
